(kicad_pcb
	(version 20260206)
	(generator "pcbnew")
	(generator_version "10.0")
	(general
		(thickness 1.6)
		(legacy_teardrops no)
	)
	(paper "A4")
	(title_block
		(title "Bryce Canyon_IOM_IOC_16318-2_OCP.brd")
		(comment 1 "Bryce Canyon / footprints 498-502 of 1605")
	)
	(layers
		(0 "F.Cu" signal "TOP")
		(4 "In1.Cu" signal "L2GND")
		(6 "In2.Cu" signal "L3")
		(8 "In3.Cu" signal "L4VCC")
		(10 "In4.Cu" signal "L5VCC")
		(12 "In5.Cu" signal "L6")
		(14 "In6.Cu" signal "L7GND")
		(2 "B.Cu" signal "BOTTOM")
		(9 "F.Adhes" user "F.Adhesive")
		(11 "B.Adhes" user "B.Adhesive")
		(13 "F.Paste" user "Package Geometry/Pastemask Top")
		(15 "B.Paste" user "Package Geometry/Pastemask Bottom")
		(5 "F.SilkS" user "Ref Des/Silkscreen Top")
		(7 "B.SilkS" user "Ref Des/Silkscreen Bottom")
		(1 "F.Mask" user "Board Geometry/Soldermask Top")
		(3 "B.Mask" user "Board Geometry/Soldermask Bottom")
		(17 "Dwgs.User" user "User.Drawings")
		(19 "Cmts.User" user "User.Comments")
		(21 "Eco1.User" user "User.Eco1")
		(23 "Eco2.User" user "User.Eco2")
		(25 "Edge.Cuts" user "Board Geometry/Outline")
		(27 "Margin" user)
		(31 "F.CrtYd" user "Package Geometry/Place Bound Top")
		(29 "B.CrtYd" user "Package Geometry/Place Bound Bottom")
		(35 "F.Fab" user "Ref Des/Assembly Top")
		(33 "B.Fab" user "Ref Des/Assembly Bottom")
	)
	(footprint ""
		(layer "F.Cu")
		(at 98.552 -144.399 90)
		(property "Reference" "R428"
			(at 0 0 90)
			(layer "F.SilkS")
			(hide yes)
			(effects
				(font
					(size 1.27 1.27)
				)
			)
		)
		(property "Value" "4K7R2F-GP"
			(at 0.064008 -3.993896 90)
			(unlocked yes)
			(layer "F.Fab")
			(hide yes)
			(effects
				(font
					(size 1.016 1.016)
					(thickness 0.1524)
				)
			)
		)
		(property "Device Type" "R402H16"
			(at 0.064008 -5.517896 90)
			(unlocked yes)
			(layer "F.Fab")
			(hide yes)
			(effects
				(font
					(size 1.016 1.016)
					(thickness 0.1524)
				)
			)
		)
		(duplicate_pad_numbers_are_jumpers no)
		(fp_line
			(start 0.508 -0.9398)
			(end -0.508 -0.9398)
			(stroke
				(width 0.1524)
				(type default)
			)
			(layer "F.SilkS")
		)
		(fp_line
			(start -0.508 -0.9398)
			(end -0.508 0.9398)
			(stroke
				(width 0.1524)
				(type default)
			)
			(layer "F.SilkS")
		)
		(fp_rect
			(start -0.508 0.9398)
			(end 0.508 -0.9398)
			(stroke
				(width 0)
				(type default)
			)
			(fill no)
			(layer "F.CrtYd")
		)
		(fp_rect
			(start -0.508 0.9398)
			(end 0.508 -0.9398)
			(stroke
				(width 0)
				(type default)
			)
			(fill no)
			(layer "F.Fab")
		)
		(pad "1" smd custom
			(at 0 -0.4445 90)
			(size 0.1397 0.1397)
			(layers "F.Cu" "F.Mask" "F.Paste")
			(net "TCA9555_A0")
			(options
				(clearance outline)
				(anchor circle)
			)
			(primitives
				(gr_poly
					(pts
						(arc
							(start -0.1778 -0.2794)
							(mid -0.249642 -0.249642)
							(end -0.2794 -0.1778)
						)
						(arc
							(start -0.2794 0.1778)
							(mid -0.249642 0.249642)
							(end -0.1778 0.2794)
						)
						(arc
							(start 0.1778 0.2794)
							(mid 0.249642 0.249642)
							(end 0.2794 0.1778)
						)
						(arc
							(start 0.2794 -0.1778)
							(mid 0.249642 -0.249642)
							(end 0.1778 -0.2794)
						)
					)
					(width 0)
					(fill yes)
				)
			)
		)
		(pad "2" smd custom
			(at 0 0.4445 90)
			(size 0.1397 0.1397)
			(layers "F.Cu" "F.Mask" "F.Paste")
			(net "GND")
			(options
				(clearance outline)
				(anchor circle)
			)
			(primitives
				(gr_poly
					(pts
						(arc
							(start -0.1778 -0.2794)
							(mid -0.249642 -0.249642)
							(end -0.2794 -0.1778)
						)
						(arc
							(start -0.2794 0.1778)
							(mid -0.249642 0.249642)
							(end -0.1778 0.2794)
						)
						(arc
							(start 0.1778 0.2794)
							(mid 0.249642 0.249642)
							(end 0.2794 0.1778)
						)
						(arc
							(start 0.2794 -0.1778)
							(mid 0.249642 -0.249642)
							(end 0.1778 -0.2794)
						)
					)
					(width 0)
					(fill yes)
				)
			)
		)
	)
	(footprint ""
		(layer "F.Cu")
		(at 53.4416 -126.8222 -90)
		(property "Reference" "R610"
			(at 0 0 270)
			(layer "F.SilkS")
			(hide yes)
			(effects
				(font
					(size 1.27 1.27)
				)
			)
		)
		(property "Value" "100KR2F-L1-GP"
			(at 0.064008 -3.993896 270)
			(unlocked yes)
			(layer "F.Fab")
			(hide yes)
			(effects
				(font
					(size 1.016 1.016)
					(thickness 0.1524)
				)
			)
		)
		(property "Device Type" "R402H16"
			(at 0.064008 -5.517896 270)
			(unlocked yes)
			(layer "F.Fab")
			(hide yes)
			(effects
				(font
					(size 1.016 1.016)
					(thickness 0.1524)
				)
			)
		)
		(duplicate_pad_numbers_are_jumpers no)
		(fp_line
			(start -0.508 -0.9398)
			(end -0.508 0.9398)
			(stroke
				(width 0.1524)
				(type default)
			)
			(layer "F.SilkS")
		)
		(fp_line
			(start 0.508 -0.9398)
			(end -0.508 -0.9398)
			(stroke
				(width 0.1524)
				(type default)
			)
			(layer "F.SilkS")
		)
		(fp_rect
			(start -0.508 0.9398)
			(end 0.508 -0.9398)
			(stroke
				(width 0)
				(type default)
			)
			(fill no)
			(layer "F.CrtYd")
		)
		(fp_rect
			(start -0.508 0.9398)
			(end 0.508 -0.9398)
			(stroke
				(width 0)
				(type default)
			)
			(fill no)
			(layer "F.Fab")
		)
		(pad "1" smd custom
			(at 0 -0.4445 270)
			(size 0.1397 0.1397)
			(layers "F.Cu" "F.Mask" "F.Paste")
			(net "FLA1_WP_N")
			(options
				(clearance outline)
				(anchor circle)
			)
			(primitives
				(gr_poly
					(pts
						(arc
							(start -0.1778 -0.2794)
							(mid -0.249642 -0.249642)
							(end -0.2794 -0.1778)
						)
						(arc
							(start -0.2794 0.1778)
							(mid -0.249642 0.249642)
							(end -0.1778 0.2794)
						)
						(arc
							(start 0.1778 0.2794)
							(mid 0.249642 0.249642)
							(end 0.2794 0.1778)
						)
						(arc
							(start 0.2794 -0.1778)
							(mid 0.249642 -0.249642)
							(end 0.1778 -0.2794)
						)
					)
					(width 0)
					(fill yes)
				)
			)
		)
		(pad "2" smd custom
			(at 0 0.4445 270)
			(size 0.1397 0.1397)
			(layers "F.Cu" "F.Mask" "F.Paste")
			(net "GND")
			(options
				(clearance outline)
				(anchor circle)
			)
			(primitives
				(gr_poly
					(pts
						(arc
							(start -0.1778 -0.2794)
							(mid -0.249642 -0.249642)
							(end -0.2794 -0.1778)
						)
						(arc
							(start -0.2794 0.1778)
							(mid -0.249642 0.249642)
							(end -0.1778 0.2794)
						)
						(arc
							(start 0.1778 0.2794)
							(mid 0.249642 0.249642)
							(end 0.2794 0.1778)
						)
						(arc
							(start 0.2794 -0.1778)
							(mid 0.249642 -0.249642)
							(end 0.1778 -0.2794)
						)
					)
					(width 0)
					(fill yes)
				)
			)
		)
	)
	(footprint ""
		(layer "F.Cu")
		(at 92.751656 -155.60548 90)
		(property "Reference" "U99"
			(at 0 0 90)
			(layer "F.SilkS")
			(hide yes)
			(effects
				(font
					(size 1.27 1.27)
				)
			)
		)
		(property "Value" "USB2514B-AEZC-TR-GP-U"
			(at -5.5372 -5.2832 90)
			(unlocked yes)
			(layer "F.Fab")
			(hide yes)
			(effects
				(font
					(size 1.016 1.016)
					(thickness 0.1524)
				)
			)
		)
		(property "Device Type" "QFN36-G3D85H40"
			(at -5.5372 -6.8072 90)
			(unlocked yes)
			(layer "F.Fab")
			(hide yes)
			(effects
				(font
					(size 1.016 1.016)
					(thickness 0.1524)
				)
			)
		)
		(duplicate_pad_numbers_are_jumpers no)
		(fp_line
			(start -4.0132 -4.0132)
			(end -2.7432 -4.0132)
			(stroke
				(width 0.1524)
				(type default)
			)
			(layer "F.SilkS")
		)
		(fp_line
			(start -0.0254 -3.7846)
			(end -0.0254 -4.2926)
			(stroke
				(width 0.1524)
				(type default)
			)
			(layer "F.SilkS")
		)
		(fp_line
			(start -4.0132 -2.7432)
			(end -4.0132 -4.0132)
			(stroke
				(width 0.1524)
				(type default)
			)
			(layer "F.SilkS")
		)
		(fp_line
			(start -3.7846 -2.0066)
			(end -4.4704 -2.0066)
			(stroke
				(width 0.1524)
				(type default)
			)
			(layer "F.SilkS")
		)
		(fp_line
			(start 4.3434 -1.524)
			(end 3.8608 -1.524)
			(stroke
				(width 0.1524)
				(type default)
			)
			(layer "F.SilkS")
		)
		(fp_line
			(start -3.8608 0.4826)
			(end -4.318 0.4826)
			(stroke
				(width 0.1524)
				(type default)
			)
			(layer "F.SilkS")
		)
		(fp_line
			(start 4.4958 0.9652)
			(end 3.81 0.9652)
			(stroke
				(width 0.1524)
				(type default)
			)
			(layer "F.SilkS")
		)
		(fp_line
			(start -1.4986 3.8354)
			(end -1.4986 4.445)
			(stroke
				(width 0.1524)
				(type default)
			)
			(layer "F.SilkS")
		)
		(fp_line
			(start 4.0132 4.0132)
			(end 4.0132 2.7432)
			(stroke
				(width 0.1524)
				(type default)
			)
			(layer "F.SilkS")
		)
		(fp_line
			(start 2.7432 4.0132)
			(end 4.0132 4.0132)
			(stroke
				(width 0.1524)
				(type default)
			)
			(layer "F.SilkS")
		)
		(fp_line
			(start -2.7432 4.0132)
			(end -4.0132 4.0132)
			(stroke
				(width 0.1524)
				(type default)
			)
			(layer "F.SilkS")
		)
		(fp_line
			(start -4.0132 4.0132)
			(end -4.0132 2.7432)
			(stroke
				(width 0.1524)
				(type default)
			)
			(layer "F.SilkS")
		)
		(fp_line
			(start 0.9906 4.318)
			(end 0.9906 3.81)
			(stroke
				(width 0.1524)
				(type default)
			)
			(layer "F.SilkS")
		)
		(fp_poly
			(pts
				(xy 2.7432 -4.0132) (xy 4.0132 -2.7432) (xy 4.0132 -4.0132)
			)
			(stroke
				(width 0)
				(type default)
			)
			(fill yes)
			(layer "F.SilkS")
		)
		(fp_rect
			(start -4.0132 4.0132)
			(end 4.0132 -4.0132)
			(stroke
				(width 0)
				(type default)
			)
			(fill no)
			(layer "F.CrtYd")
		)
		(fp_rect
			(start -4.0132 4.0132)
			(end 4.0132 -4.0132)
			(stroke
				(width 0)
				(type default)
			)
			(fill no)
			(layer "F.Fab")
		)
		(pad "1" smd rect
			(at 1.999996 -2.9591 90)
			(size 0.3048 1.0922)
			(layers "F.Cu" "F.Mask" "F.Paste")
			(net "USB_P1_DN")
		)
		(pad "2" smd rect
			(at 1.500124 -2.8702 90)
			(size 0.3048 1.27)
			(layers "F.Cu" "F.Mask" "F.Paste")
			(net "USB_P1_DP")
		)
		(pad "3" smd rect
			(at 0.999998 -2.8702 90)
			(size 0.3048 1.27)
			(layers "F.Cu" "F.Mask" "F.Paste")
			(net "USB_P2_DN")
		)
		(pad "4" smd rect
			(at 0.500126 -2.8702 90)
			(size 0.3048 1.27)
			(layers "F.Cu" "F.Mask" "F.Paste")
			(net "USB_P2_DP")
		)
		(pad "5" smd rect
			(at 0 -2.8702 90)
			(size 0.3048 1.27)
			(layers "F.Cu" "F.Mask" "F.Paste")
			(net "P3V3_STBY")
		)
		(pad "6" smd rect
			(at -0.500126 -2.8702 90)
			(size 0.3048 1.27)
			(layers "F.Cu" "F.Mask" "F.Paste")
			(net "USB_P3_DN")
		)
		(pad "7" smd rect
			(at -0.999998 -2.8702 90)
			(size 0.3048 1.27)
			(layers "F.Cu" "F.Mask" "F.Paste")
			(net "USB_P3_DP")
		)
		(pad "8" smd rect
			(at -1.500124 -2.8702 90)
			(size 0.3048 1.27)
			(layers "F.Cu" "F.Mask" "F.Paste")
			(net "Net_135")
		)
		(pad "9" smd rect
			(at -1.999996 -2.9591 90)
			(size 0.3048 1.0922)
			(layers "F.Cu" "F.Mask" "F.Paste")
			(net "Net_136")
		)
		(pad "10" smd rect
			(at -2.9591 -1.999996 90)
			(size 1.0922 0.3048)
			(layers "F.Cu" "F.Mask" "F.Paste")
			(net "P3V3_STBY")
		)
		(pad "11" smd rect
			(at -2.8702 -1.500124 90)
			(size 1.27 0.3048)
			(layers "F.Cu" "F.Mask" "F.Paste")
			(net "GND")
		)
		(pad "12" smd rect
			(at -2.8702 -0.999998 90)
			(size 1.27 0.3048)
			(layers "F.Cu" "F.Mask" "F.Paste")
			(net "USB_EN_1")
		)
		(pad "13" smd rect
			(at -2.8702 -0.500126 90)
			(size 1.27 0.3048)
			(layers "F.Cu" "F.Mask" "F.Paste")
			(net "USB_OCS_N1")
		)
		(pad "14" smd rect
			(at -2.8702 0 90)
			(size 1.27 0.3048)
			(layers "F.Cu" "F.Mask" "F.Paste")
			(net "CRFILT")
		)
		(pad "15" smd rect
			(at -2.8702 0.500126 90)
			(size 1.27 0.3048)
			(layers "F.Cu" "F.Mask" "F.Paste")
			(net "P3V3_STBY")
		)
		(pad "16" smd rect
			(at -2.8702 0.999998 90)
			(size 1.27 0.3048)
			(layers "F.Cu" "F.Mask" "F.Paste")
			(net "USB_EN_2")
		)
		(pad "17" smd rect
			(at -2.8702 1.500124 90)
			(size 1.27 0.3048)
			(layers "F.Cu" "F.Mask" "F.Paste")
			(net "USB_OCS_N2")
		)
		(pad "18" smd rect
			(at -2.9591 1.999996 90)
			(size 1.0922 0.3048)
			(layers "F.Cu" "F.Mask" "F.Paste")
			(net "USB_EN_3")
		)
		(pad "19" smd rect
			(at -1.999996 2.9591 90)
			(size 0.3048 1.0922)
			(layers "F.Cu" "F.Mask" "F.Paste")
			(net "USB_OCS_N3")
		)
		(pad "20" smd rect
			(at -1.500124 2.8702 90)
			(size 0.3048 1.27)
			(layers "F.Cu" "F.Mask" "F.Paste")
			(net "USB_EN_4")
		)
		(pad "21" smd rect
			(at -0.999998 2.8702 90)
			(size 0.3048 1.27)
			(layers "F.Cu" "F.Mask" "F.Paste")
			(net "USB_OCS_N4")
		)
		(pad "22" smd rect
			(at -0.500126 2.8702 90)
			(size 0.3048 1.27)
			(layers "F.Cu" "F.Mask" "F.Paste")
			(net "TP_USB_SDA")
		)
		(pad "23" smd rect
			(at 0 2.8702 90)
			(size 0.3048 1.27)
			(layers "F.Cu" "F.Mask" "F.Paste")
			(net "P3V3_STBY")
		)
		(pad "24" smd rect
			(at 0.500126 2.8702 90)
			(size 0.3048 1.27)
			(layers "F.Cu" "F.Mask" "F.Paste")
			(net "CFG_SEL0")
		)
		(pad "25" smd rect
			(at 0.999998 2.8702 90)
			(size 0.3048 1.27)
			(layers "F.Cu" "F.Mask" "F.Paste")
			(net "CFG_SEL1")
		)
		(pad "26" smd rect
			(at 1.500124 2.8702 90)
			(size 0.3048 1.27)
			(layers "F.Cu" "F.Mask" "F.Paste")
			(net "USB_RESET_N")
		)
		(pad "27" smd rect
			(at 1.999996 2.9591 90)
			(size 0.3048 1.0922)
			(layers "F.Cu" "F.Mask" "F.Paste")
			(net "VBUS_DET")
		)
		(pad "28" smd rect
			(at 2.9591 1.999996 90)
			(size 1.0922 0.3048)
			(layers "F.Cu" "F.Mask" "F.Paste")
			(net "USB_SUSP_IND")
		)
		(pad "29" smd rect
			(at 2.8702 1.500124 90)
			(size 1.27 0.3048)
			(layers "F.Cu" "F.Mask" "F.Paste")
			(net "P3V3_STBY")
		)
		(pad "30" smd rect
			(at 2.8702 0.999998 90)
			(size 1.27 0.3048)
			(layers "F.Cu" "F.Mask" "F.Paste")
			(net "USB_COMP_DN")
		)
		(pad "31" smd rect
			(at 2.8702 0.500126 90)
			(size 1.27 0.3048)
			(layers "F.Cu" "F.Mask" "F.Paste")
			(net "USB_COMP_DP")
		)
		(pad "32" smd rect
			(at 2.8702 0 90)
			(size 1.27 0.3048)
			(layers "F.Cu" "F.Mask" "F.Paste")
			(net "USB_HUB_XTAL_OUT")
		)
		(pad "33" smd rect
			(at 2.8702 -0.500126 90)
			(size 1.27 0.3048)
			(layers "F.Cu" "F.Mask" "F.Paste")
			(net "USB_HUB_XTAL_IN")
		)
		(pad "34" smd rect
			(at 2.8702 -0.999998 90)
			(size 1.27 0.3048)
			(layers "F.Cu" "F.Mask" "F.Paste")
			(net "PLLFILT")
		)
		(pad "35" smd rect
			(at 2.8702 -1.500124 90)
			(size 1.27 0.3048)
			(layers "F.Cu" "F.Mask" "F.Paste")
			(net "RBIAS")
		)
		(pad "36" smd rect
			(at 2.9591 -1.999996 90)
			(size 1.0922 0.3048)
			(layers "F.Cu" "F.Mask" "F.Paste")
			(net "P3V3_STBY")
		)
		(pad "37" smd rect
			(at 0 0 90)
			(size 3.8608 3.8608)
			(layers "F.Cu" "F.Mask" "F.Paste")
			(net "GND")
		)
	)
	(footprint ""
		(layer "F.Cu")
		(at 193.839338 -126.524258 180)
		(property "Reference" "C284"
			(at 0 0 180)
			(layer "F.SilkS")
			(hide yes)
			(effects
				(font
					(size 1.27 1.27)
				)
			)
		)
		(property "Value" "SCD01U25V2KX-3GP"
			(at 1.1811 -2.7051 180)
			(unlocked yes)
			(layer "F.Fab")
			(hide yes)
			(effects
				(font
					(size 1.016 1.016)
					(thickness 0.1524)
				)
			)
		)
		(property "Device Type" "C402H22"
			(at 1.1811 -4.2291 180)
			(unlocked yes)
			(layer "F.Fab")
			(hide yes)
			(effects
				(font
					(size 1.016 1.016)
					(thickness 0.1524)
				)
			)
		)
		(duplicate_pad_numbers_are_jumpers no)
		(fp_rect
			(start -0.4318 0.9525)
			(end 0.4318 -0.9525)
			(stroke
				(width 0)
				(type default)
			)
			(fill no)
			(layer "F.CrtYd")
		)
		(fp_rect
			(start -0.4318 0.9525)
			(end 0.4318 -0.9525)
			(stroke
				(width 0)
				(type default)
			)
			(fill no)
			(layer "F.Fab")
		)
		(pad "1" smd custom
			(at 0 -0.4445 180)
			(size 0.1524 0.1524)
			(layers "F.Cu" "F.Mask" "F.Paste")
			(net "VT235_VDES")
			(options
				(clearance outline)
				(anchor circle)
			)
			(primitives
				(gr_poly
					(pts
						(arc
							(start 0.3048 -0.2032)
							(mid 0.275042 -0.275042)
							(end 0.2032 -0.3048)
						)
						(arc
							(start -0.2032 -0.3048)
							(mid -0.275042 -0.275042)
							(end -0.3048 -0.2032)
						)
						(arc
							(start -0.3048 0.2032)
							(mid -0.275042 0.275042)
							(end -0.2032 0.3048)
						)
						(arc
							(start 0.2032 0.3048)
							(mid 0.275042 0.275042)
							(end 0.3048 0.2032)
						)
					)
					(width 0)
					(fill yes)
				)
			)
		)
		(pad "2" smd custom
			(at 0 0.4445 180)
			(size 0.1524 0.1524)
			(layers "F.Cu" "F.Mask" "F.Paste")
			(net "VT235_VDES_RCC")
			(options
				(clearance outline)
				(anchor circle)
			)
			(primitives
				(gr_poly
					(pts
						(arc
							(start 0.3048 -0.2032)
							(mid 0.275042 -0.275042)
							(end 0.2032 -0.3048)
						)
						(arc
							(start -0.2032 -0.3048)
							(mid -0.275042 -0.275042)
							(end -0.3048 -0.2032)
						)
						(arc
							(start -0.3048 0.2032)
							(mid -0.275042 0.275042)
							(end -0.2032 0.3048)
						)
						(arc
							(start 0.2032 0.3048)
							(mid 0.275042 0.275042)
							(end 0.3048 0.2032)
						)
					)
					(width 0)
					(fill yes)
				)
			)
		)
	)
	(footprint ""
		(layer "F.Cu")
		(at 87.501476 -68.22059 -90)
		(property "Reference" "R14"
			(at 0 0 270)
			(layer "F.SilkS")
			(hide yes)
			(effects
				(font
					(size 1.27 1.27)
				)
			)
		)
		(property "Value" "0R2J-2-GP"
			(at 0.064008 -3.993896 270)
			(unlocked yes)
			(layer "F.Fab")
			(hide yes)
			(effects
				(font
					(size 1.016 1.016)
					(thickness 0.1524)
				)
			)
		)
		(property "Device Type" "R402H16"
			(at 0.064008 -5.517896 270)
			(unlocked yes)
			(layer "F.Fab")
			(hide yes)
			(effects
				(font
					(size 1.016 1.016)
					(thickness 0.1524)
				)
			)
		)
		(duplicate_pad_numbers_are_jumpers no)
		(fp_line
			(start -0.508 -0.9398)
			(end -0.508 0.9398)
			(stroke
				(width 0.1524)
				(type default)
			)
			(layer "F.SilkS")
		)
		(fp_line
			(start 0.508 -0.9398)
			(end -0.508 -0.9398)
			(stroke
				(width 0.1524)
				(type default)
			)
			(layer "F.SilkS")
		)
		(fp_rect
			(start -0.508 0.9398)
			(end 0.508 -0.9398)
			(stroke
				(width 0)
				(type default)
			)
			(fill no)
			(layer "F.CrtYd")
		)
		(fp_rect
			(start -0.508 0.9398)
			(end 0.508 -0.9398)
			(stroke
				(width 0)
				(type default)
			)
			(fill no)
			(layer "F.Fab")
		)
		(pad "1" smd custom
			(at 0 -0.4445 270)
			(size 0.1397 0.1397)
			(layers "F.Cu" "F.Mask" "F.Paste")
			(net "NCSI_RXD0")
			(options
				(clearance outline)
				(anchor circle)
			)
			(primitives
				(gr_poly
					(pts
						(arc
							(start -0.1778 -0.2794)
							(mid -0.249642 -0.249642)
							(end -0.2794 -0.1778)
						)
						(arc
							(start -0.2794 0.1778)
							(mid -0.249642 0.249642)
							(end -0.1778 0.2794)
						)
						(arc
							(start 0.1778 0.2794)
							(mid 0.249642 0.249642)
							(end 0.2794 0.1778)
						)
						(arc
							(start 0.2794 -0.1778)
							(mid 0.249642 -0.249642)
							(end 0.1778 -0.2794)
						)
					)
					(width 0)
					(fill yes)
				)
			)
		)
		(pad "2" smd custom
			(at 0 0.4445 270)
			(size 0.1397 0.1397)
			(layers "F.Cu" "F.Mask" "F.Paste")
			(net "NCSI_RXD0_R")
			(options
				(clearance outline)
				(anchor circle)
			)
			(primitives
				(gr_poly
					(pts
						(arc
							(start -0.1778 -0.2794)
							(mid -0.249642 -0.249642)
							(end -0.2794 -0.1778)
						)
						(arc
							(start -0.2794 0.1778)
							(mid -0.249642 0.249642)
							(end -0.1778 0.2794)
						)
						(arc
							(start 0.1778 0.2794)
							(mid 0.249642 0.249642)
							(end 0.2794 0.1778)
						)
						(arc
							(start 0.2794 -0.1778)
							(mid 0.249642 -0.249642)
							(end 0.1778 -0.2794)
						)
					)
					(width 0)
					(fill yes)
				)
			)
		)
	)
)
